(kicad_pcb
	(version 20241229)
	(generator "pcbnew")
	(generator_version "9.0")
	(general
		(thickness 1.61)
		(legacy_teardrops no)
	)
	(paper "A3")
	(title_block
		(title "RDIMM DDR5 Tester")
		(date "2026-05-21")
		(rev "2.2.0")
		(company "Antmicro")
		(comment 9 "footprints 204-208 of 796")
	)
	(layers
		(0 "F.Cu" signal)
		(4 "In1.Cu" power)
		(6 "In2.Cu" mixed)
		(8 "In3.Cu" power)
		(10 "In4.Cu" mixed)
		(12 "In5.Cu" power)
		(14 "In6.Cu" mixed)
		(16 "In7.Cu" power)
		(18 "In8.Cu" power)
		(20 "In9.Cu" mixed)
		(22 "In10.Cu" power)
		(2 "B.Cu" signal)
		(9 "F.Adhes" user "F.Adhesive")
		(11 "B.Adhes" user "B.Adhesive")
		(13 "F.Paste" user)
		(15 "B.Paste" user)
		(5 "F.SilkS" user "F.Silkscreen")
		(7 "B.SilkS" user "B.Silkscreen")
		(1 "F.Mask" user)
		(3 "B.Mask" user)
		(17 "Dwgs.User" user "User.Drawings")
		(19 "Cmts.User" user "User.Comments")
		(21 "Eco1.User" user "User.Eco1")
		(23 "Eco2.User" user "User.Eco2")
		(25 "Edge.Cuts" user)
		(27 "Margin" user)
		(31 "F.CrtYd" user "F.Courtyard")
		(29 "B.CrtYd" user "B.Courtyard")
		(35 "F.Fab" user)
		(33 "B.Fab" user)
	)
	(footprint "antmicro-footprints:C_0402_1005Metric"
		(layer "F.Cu")
		(at 121.086 176.032 90)
		(descr "Capacitor SMD 0402")
		(tags "capacitor SMD 0402")
		(property "Reference" "C278"
			(at 1.21 0.41 90)
			(layer "F.SilkS")
			(effects
				(font
					(size 0.7 0.7)
					(thickness 0.15)
				)
				(justify left bottom)
			)
		)
		(property "Value" "C_100n_0402"
			(at -1.022927 2.155213 90)
			(layer "F.Fab")
			(effects
				(font
					(size 0.7 0.7)
					(thickness 0.15)
				)
				(justify left bottom)
			)
		)
		(property "Datasheet" "https://www.murata.com/products/productdetail?partno=GRM155R61H104KE14%23"
			(at 0 0 90)
			(layer "F.Fab")
			(hide yes)
			(effects
				(font
					(size 1.27 1.27)
					(thickness 0.15)
				)
			)
		)
		(property "MPN" "GRM155R61H104KE14D"
			(at 0 0 90)
			(unlocked yes)
			(layer "F.Fab")
			(hide yes)
			(effects
				(font
					(size 1 1)
					(thickness 0.15)
				)
			)
		)
		(property "Manufacturer" "Murata"
			(at 0 0 90)
			(unlocked yes)
			(layer "F.Fab")
			(hide yes)
			(effects
				(font
					(size 1 1)
					(thickness 0.15)
				)
			)
		)
		(property "License" "Apache-2.0"
			(at 0 0 90)
			(unlocked yes)
			(layer "F.Fab")
			(hide yes)
			(effects
				(font
					(size 1 1)
					(thickness 0.15)
				)
			)
		)
		(property "Author" "Antmicro"
			(at 0 0 90)
			(unlocked yes)
			(layer "F.Fab")
			(hide yes)
			(effects
				(font
					(size 1 1)
					(thickness 0.15)
				)
			)
		)
		(property "Val" "100n"
			(at 0 0 90)
			(unlocked yes)
			(layer "F.Fab")
			(hide yes)
			(effects
				(font
					(size 1 1)
					(thickness 0.15)
				)
			)
		)
		(property "Voltage" "50V"
			(at 0 0 90)
			(unlocked yes)
			(layer "F.Fab")
			(hide yes)
			(effects
				(font
					(size 1 1)
					(thickness 0.15)
				)
			)
		)
		(property "Dielectric" "X5R"
			(at 0 0 90)
			(unlocked yes)
			(layer "F.Fab")
			(hide yes)
			(effects
				(font
					(size 1 1)
					(thickness 0.15)
				)
			)
		)
		(property "Public" ""
			(at 0 0 90)
			(unlocked yes)
			(layer "F.Fab")
			(hide yes)
			(effects
				(font
					(size 1 1)
					(thickness 0.15)
				)
			)
		)
		(sheetname "/HDMI + SD Card/")
		(sheetfile "hdmi-sd-card.kicad_sch")
		(attr smd)
		(fp_rect
			(start -0.925 -0.47)
			(end 0.925 0.47)
			(stroke
				(width 0.05)
				(type default)
			)
			(fill no)
			(layer "F.CrtYd")
		)
		(fp_line
			(start 0.504 -0.25)
			(end 0.504 0.248)
			(stroke
				(width 0.15)
				(type solid)
			)
			(layer "F.Fab")
		)
		(fp_line
			(start -0.494 -0.25)
			(end 0.504 -0.25)
			(stroke
				(width 0.15)
				(type solid)
			)
			(layer "F.Fab")
		)
		(fp_line
			(start 0.504 0.248)
			(end -0.494 0.248)
			(stroke
				(width 0.15)
				(type solid)
			)
			(layer "F.Fab")
		)
		(fp_line
			(start -0.494 0.248)
			(end -0.494 -0.25)
			(stroke
				(width 0.15)
				(type solid)
			)
			(layer "F.Fab")
		)
		(fp_text user "${REFERENCE}"
			(at -0.939 4.599 90)
			(layer "F.Fab")
			(effects
				(font
					(size 0.7 0.7)
					(thickness 0.15)
				)
				(justify left bottom)
			)
		)
		(fp_text user "Author: Antmicro"
			(at -0.939 3.399 90)
			(layer "F.Fab")
			(effects
				(font
					(size 0.7 0.7)
					(thickness 0.15)
				)
				(justify left bottom)
			)
		)
		(fp_text user "License: Apache-2.0"
			(at -0.939 5.799 90)
			(layer "F.Fab")
			(effects
				(font
					(size 0.7 0.7)
					(thickness 0.15)
				)
				(justify left bottom)
			)
		)
		(pad "1" smd roundrect
			(at -0.48 0 90)
			(size 0.59 0.64)
			(layers "F.Cu" "F.Mask" "F.Paste")
			(roundrect_rratio 0.25)
			(net 810 "/HDMI + SD Card/HDMI_VDD")
			(pintype "passive")
		)
		(pad "2" smd roundrect
			(at 0.48 0 90)
			(size 0.59 0.64)
			(layers "F.Cu" "F.Mask" "F.Paste")
			(roundrect_rratio 0.25)
			(net 1 "GND")
			(pintype "passive")
		)
	)
	(footprint "antmicro-footprints:C_0402_1005Metric"
		(layer "F.Cu")
		(at 139.674499 171.149 90)
		(descr "Capacitor SMD 0402")
		(tags "capacitor SMD 0402")
		(property "Reference" "C124"
			(at -3.801 0.525501 90)
			(layer "F.SilkS")
			(effects
				(font
					(size 0.7 0.7)
					(thickness 0.15)
				)
				(justify left bottom)
			)
		)
		(property "Value" "C_100n_0402"
			(at -1.022927 2.155213 90)
			(layer "F.Fab")
			(effects
				(font
					(size 0.7 0.7)
					(thickness 0.15)
				)
				(justify left bottom)
			)
		)
		(property "Datasheet" "https://www.murata.com/products/productdetail?partno=GRM155R61H104KE14%23"
			(at 0 0 90)
			(layer "F.Fab")
			(hide yes)
			(effects
				(font
					(size 1.27 1.27)
					(thickness 0.15)
				)
			)
		)
		(property "MPN" "GRM155R61H104KE14D"
			(at 0 0 90)
			(unlocked yes)
			(layer "F.Fab")
			(hide yes)
			(effects
				(font
					(size 1 1)
					(thickness 0.15)
				)
			)
		)
		(property "Manufacturer" "Murata"
			(at 0 0 90)
			(unlocked yes)
			(layer "F.Fab")
			(hide yes)
			(effects
				(font
					(size 1 1)
					(thickness 0.15)
				)
			)
		)
		(property "License" "Apache-2.0"
			(at 0 0 90)
			(unlocked yes)
			(layer "F.Fab")
			(hide yes)
			(effects
				(font
					(size 1 1)
					(thickness 0.15)
				)
			)
		)
		(property "Author" "Antmicro"
			(at 0 0 90)
			(unlocked yes)
			(layer "F.Fab")
			(hide yes)
			(effects
				(font
					(size 1 1)
					(thickness 0.15)
				)
			)
		)
		(property "Val" "100n"
			(at 0 0 90)
			(unlocked yes)
			(layer "F.Fab")
			(hide yes)
			(effects
				(font
					(size 1 1)
					(thickness 0.15)
				)
			)
		)
		(property "Voltage" "50V"
			(at 0 0 90)
			(unlocked yes)
			(layer "F.Fab")
			(hide yes)
			(effects
				(font
					(size 1 1)
					(thickness 0.15)
				)
			)
		)
		(property "Dielectric" "X5R"
			(at 0 0 90)
			(unlocked yes)
			(layer "F.Fab")
			(hide yes)
			(effects
				(font
					(size 1 1)
					(thickness 0.15)
				)
			)
		)
		(sheetname "/Debug FTDI + VNA/")
		(sheetfile "debug-ftdi.kicad_sch")
		(attr smd)
		(fp_rect
			(start -0.925 -0.47)
			(end 0.925 0.47)
			(stroke
				(width 0.05)
				(type default)
			)
			(fill no)
			(layer "F.CrtYd")
		)
		(fp_line
			(start 0.504 -0.25)
			(end 0.504 0.248)
			(stroke
				(width 0.15)
				(type solid)
			)
			(layer "F.Fab")
		)
		(fp_line
			(start -0.494 -0.25)
			(end 0.504 -0.25)
			(stroke
				(width 0.15)
				(type solid)
			)
			(layer "F.Fab")
		)
		(fp_line
			(start 0.504 0.248)
			(end -0.494 0.248)
			(stroke
				(width 0.15)
				(type solid)
			)
			(layer "F.Fab")
		)
		(fp_line
			(start -0.494 0.248)
			(end -0.494 -0.25)
			(stroke
				(width 0.15)
				(type solid)
			)
			(layer "F.Fab")
		)
		(fp_text user "Author: Antmicro"
			(at -0.939 3.399 90)
			(layer "F.Fab")
			(effects
				(font
					(size 0.7 0.7)
					(thickness 0.15)
				)
				(justify left bottom)
			)
		)
		(fp_text user "${REFERENCE}"
			(at -0.939 4.599 90)
			(layer "F.Fab")
			(effects
				(font
					(size 0.7 0.7)
					(thickness 0.15)
				)
				(justify left bottom)
			)
		)
		(fp_text user "License: Apache-2.0"
			(at -0.939 5.799 90)
			(layer "F.Fab")
			(effects
				(font
					(size 0.7 0.7)
					(thickness 0.15)
				)
				(justify left bottom)
			)
		)
		(pad "1" smd roundrect
			(at -0.48 0 90)
			(size 0.59 0.64)
			(layers "F.Cu" "F.Mask" "F.Paste")
			(roundrect_rratio 0.25)
			(net 1 "GND")
			(pintype "passive")
		)
		(pad "2" smd roundrect
			(at 0.48 0 90)
			(size 0.59 0.64)
			(layers "F.Cu" "F.Mask" "F.Paste")
			(roundrect_rratio 0.25)
			(net 797 "+1V8")
			(pintype "passive")
		)
	)
	(footprint "antmicro-footprints:Vishay_PowerPAK_1212-8_Single"
		(layer "F.Cu")
		(at 254.9775 102.7675 180)
		(descr "PowerPAK 1212-8 Single")
		(tags "Vishay PowerPAK 1212-8 Single")
		(property "Reference" "Q27"
			(at 2.9275 2.2675 90)
			(layer "F.SilkS")
			(effects
				(font
					(size 0.7 0.7)
					(thickness 0.15)
				)
				(justify right top)
			)
		)
		(property "Value" "SI7613DN-T1-GE3"
			(at 0 2.7 0)
			(layer "F.Fab")
			(effects
				(font
					(size 0.7 0.7)
					(thickness 0.15)
				)
				(justify right top)
			)
		)
		(property "Datasheet" "https://www.vishay.com/docs/64809/si7613dn.pdf"
			(at 0 0 0)
			(layer "F.Fab")
			(hide yes)
			(effects
				(font
					(size 1.27 1.27)
					(thickness 0.15)
				)
			)
		)
		(property "MPN" "SI7613DN-T1-GE3"
			(at 0 0 180)
			(unlocked yes)
			(layer "F.Fab")
			(hide yes)
			(effects
				(font
					(size 1 1)
					(thickness 0.15)
				)
			)
		)
		(property "Manufacturer" "Vishay"
			(at 0 0 180)
			(unlocked yes)
			(layer "F.Fab")
			(hide yes)
			(effects
				(font
					(size 1 1)
					(thickness 0.15)
				)
			)
		)
		(property "Author" "Antmicro"
			(at 0 0 180)
			(unlocked yes)
			(layer "F.Fab")
			(hide yes)
			(effects
				(font
					(size 1 1)
					(thickness 0.15)
				)
			)
		)
		(property "License" "Apache-2.0"
			(at 0 0 180)
			(unlocked yes)
			(layer "F.Fab")
			(hide yes)
			(effects
				(font
					(size 1 1)
					(thickness 0.15)
				)
			)
		)
		(sheetname "/DDR5 RDIMM/")
		(sheetfile "ddr5-rdimm.kicad_sch")
		(attr smd)
		(fp_line
			(start 1.648 -1.651)
			(end 1.648 -1.317)
			(stroke
				(width 0.15)
				(type solid)
			)
			(layer "F.SilkS")
		)
		(fp_line
			(start 1.634 1.3)
			(end 1.634 1.634)
			(stroke
				(width 0.15)
				(type solid)
			)
			(layer "F.SilkS")
		)
		(fp_line
			(start -1.635 1.634)
			(end 1.634 1.634)
			(stroke
				(width 0.15)
				(type solid)
			)
			(layer "F.SilkS")
		)
		(fp_line
			(start -1.635 1.3)
			(end -1.635 1.634)
			(stroke
				(width 0.15)
				(type solid)
			)
			(layer "F.SilkS")
		)
		(fp_line
			(start -1.651 -1.651)
			(end 1.648 -1.651)
			(stroke
				(width 0.15)
				(type solid)
			)
			(layer "F.SilkS")
		)
		(fp_line
			(start -1.651 -1.651)
			(end -1.651 -1.317)
			(stroke
				(width 0.15)
				(type solid)
			)
			(layer "F.SilkS")
		)
		(fp_circle
			(center -1.9 -1.4)
			(end -1.85 -1.4)
			(stroke
				(width 0.15)
				(type solid)
			)
			(fill yes)
			(layer "F.SilkS")
		)
		(fp_rect
			(start -2 -1.8)
			(end 2 1.798)
			(stroke
				(width 0.05)
				(type solid)
			)
			(fill no)
			(layer "F.CrtYd")
		)
		(fp_line
			(start -1.6425 -1.4175)
			(end -1.4175 -1.6425)
			(stroke
				(width 0.15)
				(type solid)
			)
			(layer "F.Fab")
		)
		(fp_rect
			(start -1.651 -1.651)
			(end 1.648 1.648)
			(stroke
				(width 0.15)
				(type solid)
			)
			(fill no)
			(layer "F.Fab")
		)
		(fp_text user "License: Apache-2.0"
			(at -8 7.1 180)
			(layer "F.Fab")
			(effects
				(font
					(size 0.7 0.7)
					(thickness 0.15)
				)
				(justify left bottom)
			)
		)
		(fp_text user "${REFERENCE}"
			(at -8 4.7 180)
			(layer "F.Fab")
			(effects
				(font
					(size 0.7 0.7)
					(thickness 0.15)
				)
				(justify left bottom)
			)
		)
		(fp_text user "Author: Antmicro"
			(at -8 5.9 180)
			(layer "F.Fab")
			(effects
				(font
					(size 0.7 0.7)
					(thickness 0.15)
				)
				(justify left bottom)
			)
		)
		(pad "1" smd rect
			(at -1.436 -0.99 180)
			(size 0.99 0.405)
			(layers "F.Cu" "F.Mask" "F.Paste")
			(net 151 "+3V3")
			(pinfunction "S")
			(pintype "passive")
		)
		(pad "2" smd rect
			(at -1.436 -0.332 180)
			(size 0.99 0.405)
			(layers "F.Cu" "F.Mask" "F.Paste")
			(net 151 "+3V3")
			(pinfunction "S")
			(pintype "passive")
		)
		(pad "3" smd rect
			(at -1.436 0.33 180)
			(size 0.99 0.405)
			(layers "F.Cu" "F.Mask" "F.Paste")
			(net 151 "+3V3")
			(pinfunction "S")
			(pintype "passive")
		)
		(pad "4" smd rect
			(at -1.436 0.988 180)
			(size 0.99 0.405)
			(layers "F.Cu" "F.Mask" "F.Paste")
			(net 807 "Net-(Q26-D)")
			(pinfunction "G")
			(pintype "passive")
		)
		(pad "5" smd custom
			(at 0.557 0 180)
			(size 1.725 2.235)
			(layers "F.Cu" "F.Mask" "F.Paste")
			(net 803 "/DDR5 RDIMM/VIN_MGMT")
			(pinfunction "D")
			(pintype "passive")
			(zone_connect 2)
			(options
				(clearance outline)
				(anchor rect)
			)
			(primitives
				(gr_poly
					(pts
						(xy 0.8625 0.1275) (xy 0.8625 -0.1275) (xy 1.3725 -0.1275) (xy 1.3725 -0.5325) (xy 0.8625 -0.5325)
						(xy 0.8625 -0.7875) (xy 1.3725 -0.7875) (xy 1.3725 -1.195) (xy 0.6125 -1.195) (xy 0.6125 1.195)
						(xy 1.3725 1.195) (xy 1.3725 0.7875) (xy 0.8625 0.7875) (xy 0.8625 0.5325) (xy 1.3725 0.5325)
						(xy 1.3725 0.1275)
					)
					(width 0)
					(fill yes)
				)
			)
		)
	)
	(footprint "antmicro-footprints:R_1206_3216Metric"
		(layer "F.Cu")
		(at 246.324499 177.549 180)
		(property "Reference" "R141"
			(at 0.1 1.2 0)
			(layer "F.SilkS")
			(effects
				(font
					(size 0.7 0.7)
					(thickness 0.15)
				)
				(justify right bottom)
			)
		)
		(property "Value" "R_0R01_1206"
			(at -2.422356 2.103591 0)
			(layer "F.Fab")
			(effects
				(font
					(size 0.7 0.7)
					(thickness 0.15)
				)
				(justify right bottom)
			)
		)
		(property "Datasheet" "https://www.yageo.com/upload/media/product/productsearch/datasheet/rchip/PYu-RL_Group_521_RoHS_L_2.pdf"
			(at 0 0 180)
			(layer "F.Fab")
			(hide yes)
			(effects
				(font
					(size 1.27 1.27)
					(thickness 0.15)
				)
			)
		)
		(property "Manufacturer" "YAGEO"
			(at 0 0 180)
			(unlocked yes)
			(layer "F.Fab")
			(hide yes)
			(effects
				(font
					(size 1 1)
					(thickness 0.15)
				)
			)
		)
		(property "MPN" "RL1206FR-7W0R01L"
			(at 0 0 180)
			(unlocked yes)
			(layer "F.Fab")
			(hide yes)
			(effects
				(font
					(size 1 1)
					(thickness 0.15)
				)
			)
		)
		(property "Val" "0R01"
			(at 0 0 180)
			(unlocked yes)
			(layer "F.Fab")
			(hide yes)
			(effects
				(font
					(size 1 1)
					(thickness 0.15)
				)
			)
		)
		(property "License" "Apache-2.0"
			(at 0 0 180)
			(unlocked yes)
			(layer "F.Fab")
			(hide yes)
			(effects
				(font
					(size 1 1)
					(thickness 0.15)
				)
			)
		)
		(property "Author" "Antmicro"
			(at 0 0 180)
			(unlocked yes)
			(layer "F.Fab")
			(hide yes)
			(effects
				(font
					(size 1 1)
					(thickness 0.15)
				)
			)
		)
		(property "Tolerance" "1%"
			(at 0 0 180)
			(unlocked yes)
			(layer "F.Fab")
			(hide yes)
			(effects
				(font
					(size 1 1)
					(thickness 0.15)
				)
			)
		)
		(sheetname "/Supply/DC-DC AUX, MGT/")
		(sheetfile "dc-dc-aux-mgt.kicad_sch")
		(attr smd)
		(fp_line
			(start 0.8 0.901)
			(end -0.8 0.901)
			(stroke
				(width 0.15)
				(type solid)
			)
			(layer "F.SilkS")
		)
		(fp_line
			(start 0.8 -0.899)
			(end -0.8 -0.899)
			(stroke
				(width 0.15)
				(type solid)
			)
			(layer "F.SilkS")
		)
		(fp_rect
			(start -2.325 -1.15)
			(end 2.325 1.15)
			(stroke
				(width 0.05)
				(type default)
			)
			(fill no)
			(layer "F.CrtYd")
		)
		(fp_line
			(start 1.6 -0.802)
			(end 1.6 0.8)
			(stroke
				(width 0.15)
				(type solid)
			)
			(layer "F.Fab")
		)
		(fp_line
			(start -1.601 0.8)
			(end 1.6 0.8)
			(stroke
				(width 0.15)
				(type solid)
			)
			(layer "F.Fab")
		)
		(fp_line
			(start -1.601 -0.802)
			(end 1.6 -0.802)
			(stroke
				(width 0.15)
				(type solid)
			)
			(layer "F.Fab")
		)
		(fp_line
			(start -1.601 -0.802)
			(end -1.601 0.8)
			(stroke
				(width 0.15)
				(type solid)
			)
			(layer "F.Fab")
		)
		(fp_text user "${REFERENCE}"
			(at -2.401 3.5 180)
			(layer "F.Fab")
			(effects
				(font
					(size 0.7 0.7)
					(thickness 0.15)
				)
				(justify left bottom)
			)
		)
		(fp_text user "Author: Antmicro"
			(at -2.401 4.899 180)
			(layer "F.Fab")
			(effects
				(font
					(size 0.7 0.7)
					(thickness 0.15)
				)
				(justify left bottom)
			)
		)
		(fp_text user "License: Apache-2.0"
			(at -2.401 6.3 180)
			(layer "F.Fab")
			(effects
				(font
					(size 0.7 0.7)
					(thickness 0.15)
				)
				(justify left bottom)
			)
		)
		(pad "1" smd roundrect
			(at -1.5 0.001 180)
			(size 1.15 1.8)
			(layers "F.Cu" "F.Mask" "F.Paste")
			(roundrect_rratio 0.25)
			(net 37 "/Supply/DC-DC AUX, MGT/1V8_local")
			(pintype "passive")
		)
		(pad "2" smd roundrect
			(at 1.5 0.001 180)
			(size 1.15 1.8)
			(layers "F.Cu" "F.Mask" "F.Paste")
			(roundrect_rratio 0.25)
			(net 797 "+1V8")
			(pintype "passive")
		)
	)
	(footprint "antmicro-footprints:R_0402_1005Metric"
		(layer "F.Cu")
		(at 119.15 148.61 180)
		(descr "Resistor SMD 0402")
		(tags "resistor SMD 0402")
		(property "Reference" "R28"
			(at -5.12 -0.405 0)
			(layer "F.SilkS")
			(effects
				(font
					(size 0.7 0.7)
					(thickness 0.15)
				)
				(justify right bottom)
			)
		)
		(property "Value" "R_49k9_0402"
			(at -1.011843 1.772047 0)
			(layer "F.Fab")
			(effects
				(font
					(size 0.7 0.7)
					(thickness 0.15)
				)
				(justify right bottom)
			)
		)
		(property "Datasheet" "https://www.bourns.com/docs/product-datasheets/cr.pdf"
			(at 0 0 180)
			(layer "F.Fab")
			(hide yes)
			(effects
				(font
					(size 1.27 1.27)
					(thickness 0.15)
				)
			)
		)
		(property "MPN" "CR0402-FX-4992GLF"
			(at 0 0 180)
			(unlocked yes)
			(layer "F.Fab")
			(hide yes)
			(effects
				(font
					(size 1 1)
					(thickness 0.15)
				)
			)
		)
		(property "Manufacturer" "Bourns"
			(at 0 0 180)
			(unlocked yes)
			(layer "F.Fab")
			(hide yes)
			(effects
				(font
					(size 1 1)
					(thickness 0.15)
				)
			)
		)
		(property "License" "Apache-2.0"
			(at 0 0 180)
			(unlocked yes)
			(layer "F.Fab")
			(hide yes)
			(effects
				(font
					(size 1 1)
					(thickness 0.15)
				)
			)
		)
		(property "Author" "Antmicro"
			(at 0 0 180)
			(unlocked yes)
			(layer "F.Fab")
			(hide yes)
			(effects
				(font
					(size 1 1)
					(thickness 0.15)
				)
			)
		)
		(property "Val" "49k9"
			(at 0 0 180)
			(unlocked yes)
			(layer "F.Fab")
			(hide yes)
			(effects
				(font
					(size 1 1)
					(thickness 0.15)
				)
			)
		)
		(property "Tolerance" "1%"
			(at 0 0 180)
			(unlocked yes)
			(layer "F.Fab")
			(hide yes)
			(effects
				(font
					(size 1 1)
					(thickness 0.15)
				)
			)
		)
		(sheetname "/HDMI + SD Card/")
		(sheetfile "hdmi-sd-card.kicad_sch")
		(attr smd)
		(fp_rect
			(start -0.925 -0.47)
			(end 0.925 0.47)
			(stroke
				(width 0.05)
				(type default)
			)
			(fill no)
			(layer "F.CrtYd")
		)
		(fp_rect
			(start -0.5 -0.25)
			(end 0.5 0.25)
			(stroke
				(width 0.15)
				(type solid)
			)
			(fill no)
			(layer "F.Fab")
		)
		(fp_text user "${REFERENCE}"
			(at -0.95 3.168 180)
			(layer "F.Fab")
			(effects
				(font
					(size 0.7 0.7)
					(thickness 0.15)
				)
				(justify left bottom)
			)
		)
		(fp_text user "Author: Antmicro"
			(at -0.95 4.169 180)
			(layer "F.Fab")
			(effects
				(font
					(size 0.7 0.7)
					(thickness 0.15)
				)
				(justify left bottom)
			)
		)
		(fp_text user "License: Apache-2.0"
			(at -0.95 5.169 180)
			(layer "F.Fab")
			(effects
				(font
					(size 0.7 0.7)
					(thickness 0.15)
				)
				(justify left bottom)
			)
		)
		(pad "1" smd roundrect
			(at -0.48 0 180)
			(size 0.59 0.64)
			(layers "F.Cu" "F.Mask" "F.Paste")
			(roundrect_rratio 0.25)
			(net 674 "Net-(L4-Pad2)")
			(pintype "passive")
		)
		(pad "2" smd roundrect
			(at 0.48 0 180)
			(size 0.59 0.64)
			(layers "F.Cu" "F.Mask" "F.Paste")
			(roundrect_rratio 0.25)
			(net 322 "Net-(C300-Pad2)")
			(pintype "passive")
		)
	)
)
